(kicad_pcb
	(version 20260206)
	(generator "pcbnew")
	(generator_version "10.0")
	(general
		(thickness 1.6)
		(legacy_teardrops no)
	)
	(paper "A4")
	(title_block
		(title "04192023_DAF0TMB3IC0_F0TG_MB_C_brd_V02_OCP.brd")
		(comment 1 "Grand Teton / footprints 6060-6068 of 8354")
	)
	(layers
		(0 "F.Cu" signal "TOP")
		(4 "In1.Cu" signal "GND")
		(6 "In2.Cu" signal "IN1")
		(8 "In3.Cu" signal "GND1")
		(10 "In4.Cu" signal "IN2")
		(12 "In5.Cu" signal "GND2")
		(14 "In6.Cu" signal "IN3")
		(16 "In7.Cu" signal "GND3")
		(18 "In8.Cu" signal "VCC")
		(20 "In9.Cu" signal "VCC1")
		(22 "In10.Cu" signal "GND4")
		(24 "In11.Cu" signal "IN4")
		(26 "In12.Cu" signal "GND5")
		(28 "In13.Cu" signal "IN5")
		(30 "In14.Cu" signal "GND6")
		(32 "In15.Cu" signal "IN6")
		(34 "In16.Cu" signal "GND7")
		(2 "B.Cu" signal "BOTTOM")
		(9 "F.Adhes" user "F.Adhesive")
		(11 "B.Adhes" user "B.Adhesive")
		(13 "F.Paste" user "Package Geometry/Pastemask Top")
		(15 "B.Paste" user "Package Geometry/Pastemask Bottom")
		(5 "F.SilkS" user "Ref Des/Silkscreen Top")
		(7 "B.SilkS" user "Ref Des/Silkscreen Bottom")
		(1 "F.Mask" user "Board Geometry/Soldermask Top")
		(3 "B.Mask" user "Board Geometry/Soldermask Bottom")
		(17 "Dwgs.User" user "User.Drawings")
		(19 "Cmts.User" user "User.Comments")
		(21 "Eco1.User" user "User.Eco1")
		(23 "Eco2.User" user "User.Eco2")
		(25 "Edge.Cuts" user "Board Geometry/Outline")
		(27 "Margin" user)
		(31 "F.CrtYd" user "Package Geometry/Place Bound Top")
		(29 "B.CrtYd" user "Package Geometry/Place Bound Bottom")
		(35 "F.Fab" user "Ref Des/Assembly Top")
		(33 "B.Fab" user "Ref Des/Assembly Bottom")
	)
	(footprint ""
		(layer "B.Cu")
		(at 126.491238 -390.909302 90)
		(property "Reference" "C454"
			(at 0 0 90)
			(layer "B.SilkS")
			(hide yes)
			(effects
				(font
					(size 1.27 1.27)
				)
				(justify mirror)
			)
		)
		(property "Value" ""
			(at 0 0 90)
			(layer "B.Fab")
			(effects
				(font
					(size 1.27 1.27)
				)
				(justify mirror)
			)
		)
		(duplicate_pad_numbers_are_jumpers no)
		(fp_line
			(start 0.299974 -0.150114)
			(end -0.299974 -0.150114)
			(stroke
				(width 0.1)
				(type default)
			)
			(layer "B.Fab")
		)
		(fp_line
			(start -0.299974 -0.150114)
			(end -0.299974 0.150114)
			(stroke
				(width 0.1)
				(type default)
			)
			(layer "B.Fab")
		)
		(fp_line
			(start 0.299974 0.150114)
			(end 0.299974 -0.150114)
			(stroke
				(width 0.1)
				(type default)
			)
			(layer "B.Fab")
		)
		(fp_line
			(start -0.299974 0.150114)
			(end 0.299974 0.150114)
			(stroke
				(width 0.1)
				(type default)
			)
			(layer "B.Fab")
		)
		(pad "1" smd rect
			(at 0.2667 0 270)
			(size 0.3048 0.381)
			(layers "B.Cu" "B.Mask" "B.Paste")
			(net "P0V9_CPU1_RT_2D")
		)
		(pad "2" smd rect
			(at -0.2667 0 270)
			(size 0.3048 0.381)
			(layers "B.Cu" "B.Mask" "B.Paste")
			(net "GND")
		)
	)
	(footprint ""
		(layer "B.Cu")
		(at 454.068688 -13.102844 90)
		(property "Reference" "R3132"
			(at 0 0 90)
			(layer "B.SilkS")
			(hide yes)
			(effects
				(font
					(size 1.27 1.27)
				)
				(justify mirror)
			)
		)
		(property "Value" ""
			(at 0 0 90)
			(layer "B.Fab")
			(effects
				(font
					(size 1.27 1.27)
				)
				(justify mirror)
			)
		)
		(duplicate_pad_numbers_are_jumpers no)
		(fp_line
			(start 0.7874 -0.4064)
			(end -0.7874 -0.4064)
			(stroke
				(width 0.1524)
				(type default)
			)
			(layer "B.SilkS")
		)
		(fp_line
			(start -0.7874 -0.4064)
			(end -0.7874 0.4064)
			(stroke
				(width 0.1524)
				(type default)
			)
			(layer "B.SilkS")
		)
		(fp_line
			(start 0.7874 0.4064)
			(end 0.7874 -0.4064)
			(stroke
				(width 0.1524)
				(type default)
			)
			(layer "B.SilkS")
		)
		(fp_line
			(start -0.7874 0.4064)
			(end 0.7874 0.4064)
			(stroke
				(width 0.1524)
				(type default)
			)
			(layer "B.SilkS")
		)
		(fp_line
			(start 0.67945 -0.305054)
			(end 0.12065 -0.305054)
			(stroke
				(width 0.1)
				(type default)
			)
			(layer "B.Fab")
		)
		(fp_line
			(start 0.12065 -0.305054)
			(end 0.12065 -0.2794)
			(stroke
				(width 0.1)
				(type default)
			)
			(layer "B.Fab")
		)
		(fp_line
			(start -0.12065 -0.3048)
			(end -0.67945 -0.3048)
			(stroke
				(width 0.1)
				(type default)
			)
			(layer "B.Fab")
		)
		(fp_line
			(start -0.67945 -0.3048)
			(end -0.67945 0.3048)
			(stroke
				(width 0.1)
				(type default)
			)
			(layer "B.Fab")
		)
		(fp_line
			(start 0.12065 -0.2794)
			(end -0.12065 -0.2794)
			(stroke
				(width 0.1)
				(type default)
			)
			(layer "B.Fab")
		)
		(fp_line
			(start -0.12065 -0.2794)
			(end -0.12065 -0.3048)
			(stroke
				(width 0.1)
				(type default)
			)
			(layer "B.Fab")
		)
		(fp_line
			(start 0.12065 0.2794)
			(end 0.12065 0.3048)
			(stroke
				(width 0.1)
				(type default)
			)
			(layer "B.Fab")
		)
		(fp_line
			(start -0.120396 0.2794)
			(end 0.12065 0.2794)
			(stroke
				(width 0.1)
				(type default)
			)
			(layer "B.Fab")
		)
		(fp_line
			(start 0.67945 0.3048)
			(end 0.67945 -0.305054)
			(stroke
				(width 0.1)
				(type default)
			)
			(layer "B.Fab")
		)
		(fp_line
			(start 0.12065 0.3048)
			(end 0.67945 0.3048)
			(stroke
				(width 0.1)
				(type default)
			)
			(layer "B.Fab")
		)
		(fp_line
			(start -0.120396 0.3048)
			(end -0.120396 0.2794)
			(stroke
				(width 0.1)
				(type default)
			)
			(layer "B.Fab")
		)
		(fp_line
			(start -0.67945 0.3048)
			(end -0.120396 0.3048)
			(stroke
				(width 0.1)
				(type default)
			)
			(layer "B.Fab")
		)
		(pad "1" smd circle
			(at 0.40005 0 270)
			(size 0 0)
			(layers "B.Cu" "B.Mask" "B.Paste")
			(net "GND")
		)
		(pad "2" smd circle
			(at -0.40005 0 270)
			(size 0 0)
			(layers "B.Cu" "B.Mask" "B.Paste")
			(net "FM_OCP_SFF_PWR_GOOD")
		)
	)
	(footprint ""
		(layer "B.Cu")
		(at 416.206178 -395.148562 90)
		(property "Reference" "C793"
			(at 0 0 90)
			(layer "B.SilkS")
			(hide yes)
			(effects
				(font
					(size 1.27 1.27)
				)
				(justify mirror)
			)
		)
		(property "Value" ""
			(at 0 0 90)
			(layer "B.Fab")
			(effects
				(font
					(size 1.27 1.27)
				)
				(justify mirror)
			)
		)
		(duplicate_pad_numbers_are_jumpers no)
		(fp_line
			(start 0.299974 -0.150114)
			(end -0.299974 -0.150114)
			(stroke
				(width 0.1)
				(type default)
			)
			(layer "B.Fab")
		)
		(fp_line
			(start -0.299974 -0.150114)
			(end -0.299974 0.150114)
			(stroke
				(width 0.1)
				(type default)
			)
			(layer "B.Fab")
		)
		(fp_line
			(start 0.299974 0.150114)
			(end 0.299974 -0.150114)
			(stroke
				(width 0.1)
				(type default)
			)
			(layer "B.Fab")
		)
		(fp_line
			(start -0.299974 0.150114)
			(end 0.299974 0.150114)
			(stroke
				(width 0.1)
				(type default)
			)
			(layer "B.Fab")
		)
		(pad "1" smd rect
			(at 0.2667 0 270)
			(size 0.3048 0.381)
			(layers "B.Cu" "B.Mask" "B.Paste")
			(net "P0V9_CPU0_RT2_2A_2D")
		)
		(pad "2" smd rect
			(at -0.2667 0 270)
			(size 0.3048 0.381)
			(layers "B.Cu" "B.Mask" "B.Paste")
			(net "GND")
		)
	)
	(footprint ""
		(layer "B.Cu")
		(at 155.546298 -388.011162 -90)
		(property "Reference" "C376"
			(at 0 0 90)
			(layer "B.SilkS")
			(hide yes)
			(effects
				(font
					(size 1.27 1.27)
				)
				(justify mirror)
			)
		)
		(property "Value" ""
			(at 0 0 90)
			(layer "B.Fab")
			(effects
				(font
					(size 1.27 1.27)
				)
				(justify mirror)
			)
		)
		(duplicate_pad_numbers_are_jumpers no)
		(fp_line
			(start -0.299974 0.150114)
			(end 0.299974 0.150114)
			(stroke
				(width 0.1)
				(type default)
			)
			(layer "B.Fab")
		)
		(fp_line
			(start 0.299974 0.150114)
			(end 0.299974 -0.150114)
			(stroke
				(width 0.1)
				(type default)
			)
			(layer "B.Fab")
		)
		(fp_line
			(start -0.299974 -0.150114)
			(end -0.299974 0.150114)
			(stroke
				(width 0.1)
				(type default)
			)
			(layer "B.Fab")
		)
		(fp_line
			(start 0.299974 -0.150114)
			(end -0.299974 -0.150114)
			(stroke
				(width 0.1)
				(type default)
			)
			(layer "B.Fab")
		)
		(pad "1" smd rect
			(at 0.2667 0 90)
			(size 0.3048 0.381)
			(layers "B.Cu" "B.Mask" "B.Paste")
			(net "P1V8_CPU1_RT2_1A")
		)
		(pad "2" smd rect
			(at -0.2667 0 90)
			(size 0.3048 0.381)
			(layers "B.Cu" "B.Mask" "B.Paste")
			(net "GND")
		)
	)
	(footprint ""
		(layer "B.Cu")
		(at 357.708454 -268.41831)
		(property "Reference" "C2203"
			(at 0 0 0)
			(layer "B.SilkS")
			(hide yes)
			(effects
				(font
					(size 1.27 1.27)
				)
				(justify mirror)
			)
		)
		(property "Value" ""
			(at 0 0 0)
			(layer "B.Fab")
			(effects
				(font
					(size 1.27 1.27)
				)
				(justify mirror)
			)
		)
		(duplicate_pad_numbers_are_jumpers no)
		(fp_line
			(start -0.7874 -0.4064)
			(end -0.7874 0.4064)
			(stroke
				(width 0.1524)
				(type default)
			)
			(layer "B.SilkS")
		)
		(fp_line
			(start -0.7874 0.4064)
			(end 0.7874 0.4064)
			(stroke
				(width 0.1524)
				(type default)
			)
			(layer "B.SilkS")
		)
		(fp_line
			(start 0.7874 -0.4064)
			(end -0.7874 -0.4064)
			(stroke
				(width 0.1524)
				(type default)
			)
			(layer "B.SilkS")
		)
		(fp_line
			(start 0.7874 0.4064)
			(end 0.7874 -0.4064)
			(stroke
				(width 0.1524)
				(type default)
			)
			(layer "B.SilkS")
		)
		(fp_line
			(start -0.67945 -0.3048)
			(end -0.67945 0.3048)
			(stroke
				(width 0.1)
				(type default)
			)
			(layer "B.Fab")
		)
		(fp_line
			(start -0.67945 0.3048)
			(end -0.120396 0.3048)
			(stroke
				(width 0.1)
				(type default)
			)
			(layer "B.Fab")
		)
		(fp_line
			(start -0.12065 -0.3048)
			(end -0.67945 -0.3048)
			(stroke
				(width 0.1)
				(type default)
			)
			(layer "B.Fab")
		)
		(fp_line
			(start -0.12065 -0.2794)
			(end -0.12065 -0.3048)
			(stroke
				(width 0.1)
				(type default)
			)
			(layer "B.Fab")
		)
		(fp_line
			(start -0.120396 0.2794)
			(end 0.12065 0.2794)
			(stroke
				(width 0.1)
				(type default)
			)
			(layer "B.Fab")
		)
		(fp_line
			(start -0.120396 0.3048)
			(end -0.120396 0.2794)
			(stroke
				(width 0.1)
				(type default)
			)
			(layer "B.Fab")
		)
		(fp_line
			(start 0.12065 -0.305054)
			(end 0.12065 -0.2794)
			(stroke
				(width 0.1)
				(type default)
			)
			(layer "B.Fab")
		)
		(fp_line
			(start 0.12065 -0.2794)
			(end -0.12065 -0.2794)
			(stroke
				(width 0.1)
				(type default)
			)
			(layer "B.Fab")
		)
		(fp_line
			(start 0.12065 0.2794)
			(end 0.12065 0.3048)
			(stroke
				(width 0.1)
				(type default)
			)
			(layer "B.Fab")
		)
		(fp_line
			(start 0.12065 0.3048)
			(end 0.67945 0.3048)
			(stroke
				(width 0.1)
				(type default)
			)
			(layer "B.Fab")
		)
		(fp_line
			(start 0.67945 -0.305054)
			(end 0.12065 -0.305054)
			(stroke
				(width 0.1)
				(type default)
			)
			(layer "B.Fab")
		)
		(fp_line
			(start 0.67945 0.3048)
			(end 0.67945 -0.305054)
			(stroke
				(width 0.1)
				(type default)
			)
			(layer "B.Fab")
		)
		(pad "1" smd circle
			(at 0.40005 0 180)
			(size 0 0)
			(layers "B.Cu" "B.Mask" "B.Paste")
			(net "PVDDCR_CPU1_P0")
		)
		(pad "2" smd circle
			(at -0.40005 0 180)
			(size 0 0)
			(layers "B.Cu" "B.Mask" "B.Paste")
			(net "GND")
		)
	)
	(footprint ""
		(layer "B.Cu")
		(at 382.491234 -399.291302 90)
		(property "Reference" "C1016"
			(at 0 0 90)
			(layer "B.SilkS")
			(hide yes)
			(effects
				(font
					(size 1.27 1.27)
				)
				(justify mirror)
			)
		)
		(property "Value" ""
			(at 0 0 90)
			(layer "B.Fab")
			(effects
				(font
					(size 1.27 1.27)
				)
				(justify mirror)
			)
		)
		(duplicate_pad_numbers_are_jumpers no)
		(fp_line
			(start 0.299974 -0.150114)
			(end -0.299974 -0.150114)
			(stroke
				(width 0.1)
				(type default)
			)
			(layer "B.Fab")
		)
		(fp_line
			(start -0.299974 -0.150114)
			(end -0.299974 0.150114)
			(stroke
				(width 0.1)
				(type default)
			)
			(layer "B.Fab")
		)
		(fp_line
			(start 0.299974 0.150114)
			(end 0.299974 -0.150114)
			(stroke
				(width 0.1)
				(type default)
			)
			(layer "B.Fab")
		)
		(fp_line
			(start -0.299974 0.150114)
			(end 0.299974 0.150114)
			(stroke
				(width 0.1)
				(type default)
			)
			(layer "B.Fab")
		)
		(pad "1" smd rect
			(at 0.2667 0 270)
			(size 0.3048 0.381)
			(layers "B.Cu" "B.Mask" "B.Paste")
			(net "P0V9_CPU0_RT_2D")
		)
		(pad "2" smd rect
			(at -0.2667 0 270)
			(size 0.3048 0.381)
			(layers "B.Cu" "B.Mask" "B.Paste")
			(net "GND")
		)
	)
	(footprint ""
		(layer "B.Cu")
		(at 155.491434 -316.049152 90)
		(property "Reference" "C239"
			(at 0 0 90)
			(layer "B.SilkS")
			(hide yes)
			(effects
				(font
					(size 1.27 1.27)
				)
				(justify mirror)
			)
		)
		(property "Value" ""
			(at 0 0 90)
			(layer "B.Fab")
			(effects
				(font
					(size 1.27 1.27)
				)
				(justify mirror)
			)
		)
		(duplicate_pad_numbers_are_jumpers no)
		(fp_line
			(start 0.7874 -0.4064)
			(end -0.7874 -0.4064)
			(stroke
				(width 0.1524)
				(type default)
			)
			(layer "B.SilkS")
		)
		(fp_line
			(start -0.7874 -0.4064)
			(end -0.7874 0.4064)
			(stroke
				(width 0.1524)
				(type default)
			)
			(layer "B.SilkS")
		)
		(fp_line
			(start 0.7874 0.4064)
			(end 0.7874 -0.4064)
			(stroke
				(width 0.1524)
				(type default)
			)
			(layer "B.SilkS")
		)
		(fp_line
			(start -0.7874 0.4064)
			(end 0.7874 0.4064)
			(stroke
				(width 0.1524)
				(type default)
			)
			(layer "B.SilkS")
		)
		(fp_line
			(start 0.67945 -0.305054)
			(end 0.12065 -0.305054)
			(stroke
				(width 0.1)
				(type default)
			)
			(layer "B.Fab")
		)
		(fp_line
			(start 0.12065 -0.305054)
			(end 0.12065 -0.2794)
			(stroke
				(width 0.1)
				(type default)
			)
			(layer "B.Fab")
		)
		(fp_line
			(start -0.12065 -0.3048)
			(end -0.67945 -0.3048)
			(stroke
				(width 0.1)
				(type default)
			)
			(layer "B.Fab")
		)
		(fp_line
			(start -0.67945 -0.3048)
			(end -0.67945 0.3048)
			(stroke
				(width 0.1)
				(type default)
			)
			(layer "B.Fab")
		)
		(fp_line
			(start 0.12065 -0.2794)
			(end -0.12065 -0.2794)
			(stroke
				(width 0.1)
				(type default)
			)
			(layer "B.Fab")
		)
		(fp_line
			(start -0.12065 -0.2794)
			(end -0.12065 -0.3048)
			(stroke
				(width 0.1)
				(type default)
			)
			(layer "B.Fab")
		)
		(fp_line
			(start 0.12065 0.2794)
			(end 0.12065 0.3048)
			(stroke
				(width 0.1)
				(type default)
			)
			(layer "B.Fab")
		)
		(fp_line
			(start -0.120396 0.2794)
			(end 0.12065 0.2794)
			(stroke
				(width 0.1)
				(type default)
			)
			(layer "B.Fab")
		)
		(fp_line
			(start 0.67945 0.3048)
			(end 0.67945 -0.305054)
			(stroke
				(width 0.1)
				(type default)
			)
			(layer "B.Fab")
		)
		(fp_line
			(start 0.12065 0.3048)
			(end 0.67945 0.3048)
			(stroke
				(width 0.1)
				(type default)
			)
			(layer "B.Fab")
		)
		(fp_line
			(start -0.120396 0.3048)
			(end -0.120396 0.2794)
			(stroke
				(width 0.1)
				(type default)
			)
			(layer "B.Fab")
		)
		(fp_line
			(start -0.67945 0.3048)
			(end -0.120396 0.3048)
			(stroke
				(width 0.1)
				(type default)
			)
			(layer "B.Fab")
		)
		(pad "1" smd circle
			(at 0.40005 0 270)
			(size 0 0)
			(layers "B.Cu" "B.Mask" "B.Paste")
			(net "XTAL_CPU1_R_X32K_X2")
		)
		(pad "2" smd circle
			(at -0.40005 0 270)
			(size 0 0)
			(layers "B.Cu" "B.Mask" "B.Paste")
			(net "GND")
		)
	)
	(footprint ""
		(layer "B.Cu")
		(at 59.378596 -386.766562 90)
		(property "Reference" "C266"
			(at 0 0 90)
			(layer "B.SilkS")
			(hide yes)
			(effects
				(font
					(size 1.27 1.27)
				)
				(justify mirror)
			)
		)
		(property "Value" ""
			(at 0 0 90)
			(layer "B.Fab")
			(effects
				(font
					(size 1.27 1.27)
				)
				(justify mirror)
			)
		)
		(duplicate_pad_numbers_are_jumpers no)
		(fp_line
			(start 0.299974 -0.150114)
			(end -0.299974 -0.150114)
			(stroke
				(width 0.1)
				(type default)
			)
			(layer "B.Fab")
		)
		(fp_line
			(start -0.299974 -0.150114)
			(end -0.299974 0.150114)
			(stroke
				(width 0.1)
				(type default)
			)
			(layer "B.Fab")
		)
		(fp_line
			(start 0.299974 0.150114)
			(end 0.299974 -0.150114)
			(stroke
				(width 0.1)
				(type default)
			)
			(layer "B.Fab")
		)
		(fp_line
			(start -0.299974 0.150114)
			(end 0.299974 0.150114)
			(stroke
				(width 0.1)
				(type default)
			)
			(layer "B.Fab")
		)
		(pad "1" smd rect
			(at 0.2667 0 270)
			(size 0.3048 0.381)
			(layers "B.Cu" "B.Mask" "B.Paste")
			(net "P0V9_CPU1_RT_2D")
		)
		(pad "2" smd rect
			(at -0.2667 0 270)
			(size 0.3048 0.381)
			(layers "B.Cu" "B.Mask" "B.Paste")
			(net "GND")
		)
	)
	(footprint ""
		(layer "B.Cu")
		(at 51.128422 -194.9196 180)
		(property "Reference" "R1581"
			(at 0 0 0)
			(layer "B.SilkS")
			(hide yes)
			(effects
				(font
					(size 1.27 1.27)
				)
				(justify mirror)
			)
		)
		(property "Value" ""
			(at 0 0 0)
			(layer "B.Fab")
			(effects
				(font
					(size 1.27 1.27)
				)
				(justify mirror)
			)
		)
		(duplicate_pad_numbers_are_jumpers no)
		(fp_line
			(start 0.7874 0.4064)
			(end 0.7874 -0.4064)
			(stroke
				(width 0.1524)
				(type default)
			)
			(layer "B.SilkS")
		)
		(fp_line
			(start 0.7874 -0.4064)
			(end -0.7874 -0.4064)
			(stroke
				(width 0.1524)
				(type default)
			)
			(layer "B.SilkS")
		)
		(fp_line
			(start -0.7874 0.4064)
			(end 0.7874 0.4064)
			(stroke
				(width 0.1524)
				(type default)
			)
			(layer "B.SilkS")
		)
		(fp_line
			(start -0.7874 -0.4064)
			(end -0.7874 0.4064)
			(stroke
				(width 0.1524)
				(type default)
			)
			(layer "B.SilkS")
		)
		(fp_line
			(start 0.67945 0.3048)
			(end 0.67945 -0.305054)
			(stroke
				(width 0.1)
				(type default)
			)
			(layer "B.Fab")
		)
		(fp_line
			(start 0.67945 -0.305054)
			(end 0.12065 -0.305054)
			(stroke
				(width 0.1)
				(type default)
			)
			(layer "B.Fab")
		)
		(fp_line
			(start 0.12065 0.3048)
			(end 0.67945 0.3048)
			(stroke
				(width 0.1)
				(type default)
			)
			(layer "B.Fab")
		)
		(fp_line
			(start 0.12065 0.2794)
			(end 0.12065 0.3048)
			(stroke
				(width 0.1)
				(type default)
			)
			(layer "B.Fab")
		)
		(fp_line
			(start 0.12065 -0.2794)
			(end -0.12065 -0.2794)
			(stroke
				(width 0.1)
				(type default)
			)
			(layer "B.Fab")
		)
		(fp_line
			(start 0.12065 -0.305054)
			(end 0.12065 -0.2794)
			(stroke
				(width 0.1)
				(type default)
			)
			(layer "B.Fab")
		)
		(fp_line
			(start -0.120396 0.3048)
			(end -0.120396 0.2794)
			(stroke
				(width 0.1)
				(type default)
			)
			(layer "B.Fab")
		)
		(fp_line
			(start -0.120396 0.2794)
			(end 0.12065 0.2794)
			(stroke
				(width 0.1)
				(type default)
			)
			(layer "B.Fab")
		)
		(fp_line
			(start -0.12065 -0.2794)
			(end -0.12065 -0.3048)
			(stroke
				(width 0.1)
				(type default)
			)
			(layer "B.Fab")
		)
		(fp_line
			(start -0.12065 -0.3048)
			(end -0.67945 -0.3048)
			(stroke
				(width 0.1)
				(type default)
			)
			(layer "B.Fab")
		)
		(fp_line
			(start -0.67945 0.3048)
			(end -0.120396 0.3048)
			(stroke
				(width 0.1)
				(type default)
			)
			(layer "B.Fab")
		)
		(fp_line
			(start -0.67945 -0.3048)
			(end -0.67945 0.3048)
			(stroke
				(width 0.1)
				(type default)
			)
			(layer "B.Fab")
		)
		(pad "1" smd circle
			(at 0.40005 0)
			(size 0 0)
			(layers "B.Cu" "B.Mask" "B.Paste")
			(net "I3C_SPD_DDRAF_CPU1_SCL")
		)
		(pad "2" smd circle
			(at -0.40005 0)
			(size 0 0)
			(layers "B.Cu" "B.Mask" "B.Paste")
			(net "I3C_SPD_DDRB_CPU1_SCL")
		)
	)
)
